# BASEBOARD_FAB2 (Tioga Pass) — schematic netlist excerpt (pin names and nets, part order shuffled) for the footprints in the layout excerpt that follows; sources: Cadence DE-HDL packaged netlist, KiCad conversion of Wiwynn_Tioga_Pass_MB.brd

J1G1  SCONN288_H44441004  SCONN  pkg PIP  page 77
  \12v\(1)  = P12V_NVDIMM_GHJ
  VSS(93)  = GND
  DQ(4)  = M_G_DQ<5>
  VSS(92)  = GND
  DQ(0)  = M_G_DQ<1>
  VSS(91)  = GND
  DQS9P  = M_G_DQS_DP<9>
  DQS9N  = M_G_DQS_DN<9>
  VSS(90)  = GND
  DQ(6)  = M_G_DQ<7>
  VSS(89)  = GND
  DQ(2)  = M_G_DQ<3>
  VSS(88)  = GND
  DQ(12)  = M_G_DQ<13>
  VSS(87)  = GND
  DQ(8)  = M_G_DQ<9>
  VSS(86)  = GND
  DQS10P  = M_G_DQS_DP<10>
  DQS10N  = M_G_DQS_DN<10>
  VSS(85)  = GND
  DQ(14)  = M_G_DQ<15>
  VSS(84)  = GND
  DQ(10)  = M_G_DQ<11>
  VSS(83)  = GND
  DQ(20)  = M_G_DQ<21>
  VSS(82)  = GND
  DQ(16)  = M_G_DQ<17>
  VSS(81)  = GND
  DQS11P  = M_G_DQS_DP<11>
  DQS11N  = M_G_DQS_DN<11>
  VSS(80)  = GND
  DQ(22)  = M_G_DQ<23>
  VSS(79)  = GND
  DQ(18)  = M_G_DQ<19>
  VSS(78)  = GND
  DQ(28)  = M_G_DQ<29>
  VSS(77)  = GND
  DQ(24)  = M_G_DQ<25>
  VSS(76)  = GND
  DQS12P  = M_G_DQS_DP<12>
  DQS12N  = M_G_DQS_DN<12>
  VSS(75)  = GND
  DQ(30)  = M_G_DQ<31>
  VSS(74)  = GND
  DQ(26)  = M_G_DQ<27>
  VSS(73)  = GND
  CB(4)  = M_G_ECC<5>
  VSS(72)  = GND
  CB(0)  = M_G_ECC<1>
  VSS(71)  = GND
  DQS17P  = M_G_DQS_DP<17>
  DQS17N  = M_G_DQS_DN<17>
  VSS(70)  = GND
  CB(6)  = M_G_ECC<7>
  VSS(69)  = GND
  CB(2)  = M_G_ECC<3>
  VSS(68)  = GND
  RESET_N  = M_GHJ_RST_N
  VDD(25)  = PVDDQ_GHJ
  CKE(0)  = M_G_CKE<0>
  VDD(24)  = PVDDQ_GHJ
  ACT_N  = M_G_ACT_N
  BG(0)  = M_G_BG<0>
  VDD(23)  = PVDDQ_GHJ
  A12  = M_G_MA<12>
  A9  = M_G_MA<9>
  VDD(22)  = PVDDQ_GHJ
  A8  = M_G_MA<8>
  A6  = M_G_MA<6>
  VDD(21)  = PVDDQ_GHJ
  A3  = M_G_MA<3>
  A1  = M_G_MA<1>
  VDD(20)  = PVDDQ_GHJ
  CK0P  = M_G_CLK_DP<0>
  CK0N  = M_G_CLK_DN<0>
  VDD(19)  = PVDDQ_GHJ
  VTT(1)  = PVTT_GHJ
  EVENT_N  = FM_DIMM_EVENT_COD_N
  A0  = M_G_MA<0>
  VDD(18)  = PVDDQ_GHJ
  BA(0)  = M_G_BA<0>
  A16_RAS_N  = M_G_MA<16>
  VDD(17)  = PVDDQ_GHJ
  S0_N  = M_G_CS_N<0>
  VDD(16)  = PVDDQ_GHJ
  A15_CAS_N  = M_G_MA<15>
  ODT(0)  = M_G_ODT<0>
  VDD(15)  = PVDDQ_GHJ
  S1_N  = M_G_CS_N<1>
  VDD(14)  = PVDDQ_GHJ
  ODT(1)  = M_G_ODT<1>
  VDD(13)  = PVDDQ_GHJ
  S2_N_C(0)  = M_G_CS_N<2>
  VSS(67)  = GND
  DQ(36)  = M_G_DQ<37>
  VSS(66)  = GND
  DQ(32)  = M_G_DQ<33>
  VSS(65)  = GND
  DQS13P  = M_G_DQS_DP<13>
  DQS13N  = M_G_DQS_DN<13>
  VSS(64)  = GND
  DQ(38)  = M_G_DQ<39>
  VSS(63)  = GND
  DQ(34)  = M_G_DQ<35>
  VSS(62)  = GND
  DQ(44)  = M_G_DQ<45>
  VSS(61)  = GND
  DQ(40)  = M_G_DQ<41>
  VSS(60)  = GND
  DQS14P  = M_G_DQS_DP<14>
  DQS14N  = M_G_DQS_DN<14>
  VSS(59)  = GND
  DQ(46)  = M_G_DQ<47>
  VSS(58)  = GND
  DQ(42)  = M_G_DQ<43>
  VSS(57)  = GND
  DQ(52)  = M_G_DQ<53>
  VSS(56)  = GND
  DQ(48)  = M_G_DQ<49>
  VSS(55)  = GND
  DQS15P  = M_G_DQS_DP<15>
  DQS15N  = M_G_DQS_DN<15>
  VSS(54)  = GND
  DQ(54)  = M_G_DQ<55>
  VSS(53)  = GND
  DQ(50)  = M_G_DQ<51>
  VSS(52)  = GND
  DQ(60)  = M_G_DQ<61>
  VSS(51)  = GND
  DQ(56)  = M_G_DQ<57>
  VSS(50)  = GND
  DQS16P  = M_G_DQS_DP<16>
  DQS16N  = M_G_DQS_DN<16>
  VSS(49)  = GND
  DQ(62)  = M_G_DQ<63>
  VSS(48)  = GND
  DQ(58)  = M_G_DQ<59>
  VSS(47)  = GND
  SA(0)  = GND
  SA(1)  = GND
  SCL  = SMB_DDR_GHJ_VPP_SCL
  VPP(4)  = PVPP_GHJ
  VPP(3)  = PVPP_GHJ
  RFU(2)  = TP_CH_G_DIMM_G0_RFU_2
  \12v\(0)  = P12V_NVDIMM_GHJ
  VREFCA  = M_G_VREF
  VSS(46)  = GND
  DQ(5)  = M_G_DQ<4>
  VSS(45)  = GND
  DQ(1)  = M_G_DQ<0>
  VSS(44)  = GND
  DQS0N  = M_G_DQS_DN<0>
  DQS0P  = M_G_DQS_DP<0>
  VSS(43)  = GND
  DQ(7)  = M_G_DQ<6>
  VSS(42)  = GND
  DQ(3)  = M_G_DQ<2>
  VSS(41)  = GND
  DQ(13)  = M_G_DQ<12>
  VSS(40)  = GND
  DQ(9)  = M_G_DQ<8>
  VSS(39)  = GND
  DQS1N  = M_G_DQS_DN<1>
  DQS1P  = M_G_DQS_DP<1>
  VSS(38)  = GND
  DQ(15)  = M_G_DQ<14>
  VSS(37)  = GND
  DQ(11)  = M_G_DQ<10>
  VSS(36)  = GND
  DQ(21)  = M_G_DQ<20>
  VSS(35)  = GND
  DQ(17)  = M_G_DQ<16>
  VSS(34)  = GND
  DQS2N  = M_G_DQS_DN<2>
  DQS2P  = M_G_DQS_DP<2>
  VSS(33)  = GND
  DQ(23)  = M_G_DQ<22>
  VSS(32)  = GND
  DQ(19)  = M_G_DQ<18>
  VSS(31)  = GND
  DQ(29)  = M_G_DQ<28>
  VSS(30)  = GND
  DQ(25)  = M_G_DQ<24>
  VSS(29)  = GND
  DQS3N  = M_G_DQS_DN<3>
  DQS3P  = M_G_DQS_DP<3>
  VSS(28)  = GND
  DQ(31)  = M_G_DQ<30>
  VSS(27)  = GND
  DQ(27)  = M_G_DQ<26>
  VSS(26)  = GND
  CB(5)  = M_G_ECC<4>
  VSS(25)  = GND
  CB(1)  = M_G_ECC<0>
  VSS(24)  = GND
  DQS8N  = M_G_DQS_DN<8>
  DQS8P  = M_G_DQS_DP<8>
  VSS(23)  = GND
  CB(7)  = M_G_ECC<6>
  VSS(22)  = GND
  CB(3)  = M_G_ECC<2>
  VSS(21)  = GND
  CKE(1)  = M_G_CKE<1>
  VDD(12)  = PVDDQ_GHJ
  RFU(0)  = TP_CH_G_DIMM_G0_RFU_0
  VDD(11)  = PVDDQ_GHJ
  BG(1)  = M_G_BG<1>
  ALERT_N  = M_G_ALERT_N
  VDD(10)  = PVDDQ_GHJ
  A11  = M_G_MA<11>
  A7  = M_G_MA<7>
  VDD(9)  = PVDDQ_GHJ
  A5  = M_G_MA<5>
  A4  = M_G_MA<4>
  VDD(8)  = PVDDQ_GHJ
  A2  = M_G_MA<2>
  VDD(7)  = PVDDQ_GHJ
  CK1P  = M_G_CLK_DP<1>
  CK1N  = M_G_CLK_DN<1>
  VDD(6)  = PVDDQ_GHJ
  VTT(0)  = PVTT_GHJ
  PAR  = M_G_PAR
  VDD(5)  = PVDDQ_GHJ
  BA(1)  = M_G_BA<1>
  A10  = M_G_MA<10>
  VDD(4)  = PVDDQ_GHJ
  RFU(1)  = TP_CH_G_DIMM_G0_RFU_1
  A14_WE_N  = M_G_MA<14>
  VDD(3)  = PVDDQ_GHJ
  SAVE_N_NC  = FM_ADR_COMPLETE_GHJ_N
  VDD(2)  = PVDDQ_GHJ
  A13  = M_G_MA<13>
  VDD(1)  = PVDDQ_GHJ
  A17  = M_G_MA<17>
  C(2)  = M_G_C<2>
  VDD(0)  = PVDDQ_GHJ
  S3_N_C(1)  = M_G_CS_N<3>
  SA(2)  = GND
  VSS(20)  = GND
  DQ(37)  = M_G_DQ<36>
  VSS(19)  = GND
  DQ(33)  = M_G_DQ<32>
  VSS(18)  = GND
  DQS4N  = M_G_DQS_DN<4>
  DQS4P  = M_G_DQS_DP<4>
  VSS(17)  = GND
  DQ(39)  = M_G_DQ<38>
  VSS(16)  = GND
  DQ(35)  = M_G_DQ<34>
  VSS(15)  = GND
  DQ(45)  = M_G_DQ<44>
  VSS(14)  = GND
  DQ(41)  = M_G_DQ<40>
  VSS(13)  = GND
  DQS5N  = M_G_DQS_DN<5>
  DQS5P  = M_G_DQS_DP<5>
  VSS(12)  = GND
  DQ(47)  = M_G_DQ<46>
  VSS(11)  = GND
  DQ(43)  = M_G_DQ<42>
  VSS(10)  = GND
  DQ(53)  = M_G_DQ<52>
  VSS(9)  = GND
  DQ(49)  = M_G_DQ<48>
  VSS(8)  = GND
  DQS6N  = M_G_DQS_DN<6>
  DQS6P  = M_G_DQS_DP<6>
  VSS(7)  = GND
  DQ(55)  = M_G_DQ<54>
  VSS(6)  = GND
  DQ(51)  = M_G_DQ<50>
  VSS(5)  = GND
  DQ(61)  = M_G_DQ<60>
  VSS(4)  = GND
  DQ(57)  = M_G_DQ<56>
  VSS(3)  = GND
  DQS7N  = M_G_DQS_DN<7>
  DQS7P  = M_G_DQS_DP<7>
  VSS(2)  = GND
  DQ(63)  = M_G_DQ<62>
  VSS(1)  = GND
  DQ(59)  = M_G_DQ<58>
  VSS(0)  = GND
  VDDSPD  = PVPP_GHJ
  SDA  = SMB_DDR_GHJ_VPP_SDA
  VPP(1)  = PVPP_GHJ
  VPP(0)  = PVPP_GHJ
  VPP(2)  = PVPP_GHJ

(kicad_pcb
	(version 20260206)
	(generator "pcbnew")
	(generator_version "10.0")
	(general
		(thickness 1.6)
		(legacy_teardrops no)
	)
	(paper "A4")
	(title_block
		(title "Wiwynn_Tioga_Pass_MB.brd")
		(comment 1 "Tioga Pass / footprint 2018 of 4770 (J1G1), pads 101-151 of 291")
	)
	(layers
		(0 "F.Cu" signal "TOP")
		(4 "In1.Cu" signal "L2GND")
		(6 "In2.Cu" signal "L3")
		(8 "In3.Cu" signal "L4GND")
		(10 "In4.Cu" signal "L5")
		(12 "In5.Cu" signal "L6GND")
		(14 "In6.Cu" signal "L7VCC")
		(16 "In7.Cu" signal "L8VCC")
		(18 "In8.Cu" signal "L9GND")
		(20 "In9.Cu" signal "L10")
		(22 "In10.Cu" signal "L11GND")
		(24 "In11.Cu" signal "L12")
		(26 "In12.Cu" signal "L13GND")
		(2 "B.Cu" signal "BOTTOM")
		(9 "F.Adhes" user "F.Adhesive")
		(11 "B.Adhes" user "B.Adhesive")
		(13 "F.Paste" user "Package Geometry/Pastemask Top")
		(15 "B.Paste" user "Package Geometry/Pastemask Bottom")
		(5 "F.SilkS" user "Ref Des/Silkscreen Top")
		(7 "B.SilkS" user "Ref Des/Silkscreen Bottom")
		(1 "F.Mask" user "Board Geometry/Soldermask Top")
		(3 "B.Mask" user "Board Geometry/Soldermask Bottom")
		(17 "Dwgs.User" user "User.Drawings")
		(19 "Cmts.User" user "User.Comments")
		(21 "Eco1.User" user "User.Eco1")
		(23 "Eco2.User" user "User.Eco2")
		(25 "Edge.Cuts" user "Board Geometry/Outline")
		(27 "Margin" user)
		(31 "F.CrtYd" user "Package Geometry/Place Bound Top")
		(29 "B.CrtYd" user "Package Geometry/Place Bound Bottom")
		(35 "F.Fab" user "Ref Des/Assembly Top")
		(33 "B.Fab" user "Ref Des/Assembly Bottom")
	)
	(footprint ""
		(layer "F.Cu")
		(at 29.699458 -15.423642 90)
		(property "Reference" "J1G1"
			(at 9.314688 35.070542 0)
			(unlocked yes)
			(layer "F.SilkS")
			(effects
				(font
					(size 0.7874 0.5842)
					(thickness 0.1524)
				)
				(justify left)
			)
		)
		(property "Value" ""
			(at 0 0 90)
			(layer "F.Fab")
			(effects
				(font
					(size 1.27 1.27)
				)
			)
		)
		(duplicate_pad_numbers_are_jumpers no)
		(pad "98" smd rect
			(at 0 87.54999 90)
			(size 1.8034 0.508)
			(layers "F.Cu" "F.Mask" "F.Paste")
			(net "GND")
		)
		(pad "99" smd rect
			(at 0 88.399874 90)
			(size 1.8034 0.508)
			(layers "F.Cu" "F.Mask" "F.Paste")
			(net "M_G_DQS_DP<13>")
		)
		(pad "100" smd rect
			(at 0 89.250012 90)
			(size 1.8034 0.508)
			(layers "F.Cu" "F.Mask" "F.Paste")
			(net "M_G_DQS_DN<13>")
		)
		(pad "101" smd rect
			(at 0 90.099896 90)
			(size 1.8034 0.508)
			(layers "F.Cu" "F.Mask" "F.Paste")
			(net "GND")
		)
		(pad "102" smd rect
			(at 0 90.950034 90)
			(size 1.8034 0.508)
			(layers "F.Cu" "F.Mask" "F.Paste")
			(net "M_G_DQ<39>")
		)
		(pad "103" smd rect
			(at 0 91.799918 90)
			(size 1.8034 0.508)
			(layers "F.Cu" "F.Mask" "F.Paste")
			(net "GND")
		)
		(pad "104" smd rect
			(at 0 92.650056 90)
			(size 1.8034 0.508)
			(layers "F.Cu" "F.Mask" "F.Paste")
			(net "M_G_DQ<35>")
		)
		(pad "105" smd rect
			(at 0 93.49994 90)
			(size 1.8034 0.508)
			(layers "F.Cu" "F.Mask" "F.Paste")
			(net "GND")
		)
		(pad "106" smd rect
			(at 0 94.350078 90)
			(size 1.8034 0.508)
			(layers "F.Cu" "F.Mask" "F.Paste")
			(net "M_G_DQ<45>")
		)
		(pad "107" smd rect
			(at 0 95.199962 90)
			(size 1.8034 0.508)
			(layers "F.Cu" "F.Mask" "F.Paste")
			(net "GND")
		)
		(pad "108" smd rect
			(at 0 96.0501 90)
			(size 1.8034 0.508)
			(layers "F.Cu" "F.Mask" "F.Paste")
			(net "M_G_DQ<41>")
		)
		(pad "109" smd rect
			(at 0 96.899984 90)
			(size 1.8034 0.508)
			(layers "F.Cu" "F.Mask" "F.Paste")
			(net "GND")
		)
		(pad "110" smd rect
			(at 0 97.750122 90)
			(size 1.8034 0.508)
			(layers "F.Cu" "F.Mask" "F.Paste")
			(net "M_G_DQS_DP<14>")
		)
		(pad "111" smd rect
			(at 0 98.600006 90)
			(size 1.8034 0.508)
			(layers "F.Cu" "F.Mask" "F.Paste")
			(net "M_G_DQS_DN<14>")
		)
		(pad "112" smd rect
			(at 0 99.44989 90)
			(size 1.8034 0.508)
			(layers "F.Cu" "F.Mask" "F.Paste")
			(net "GND")
		)
		(pad "113" smd rect
			(at 0 100.300028 90)
			(size 1.8034 0.508)
			(layers "F.Cu" "F.Mask" "F.Paste")
			(net "M_G_DQ<47>")
		)
		(pad "114" smd rect
			(at 0 101.149912 90)
			(size 1.8034 0.508)
			(layers "F.Cu" "F.Mask" "F.Paste")
			(net "GND")
		)
		(pad "115" smd rect
			(at 0 102.00005 90)
			(size 1.8034 0.508)
			(layers "F.Cu" "F.Mask" "F.Paste")
			(net "M_G_DQ<43>")
		)
		(pad "116" smd rect
			(at 0 102.849934 90)
			(size 1.8034 0.508)
			(layers "F.Cu" "F.Mask" "F.Paste")
			(net "GND")
		)
		(pad "117" smd rect
			(at 0 103.700072 90)
			(size 1.8034 0.508)
			(layers "F.Cu" "F.Mask" "F.Paste")
			(net "M_G_DQ<53>")
		)
		(pad "118" smd rect
			(at 0 104.549956 90)
			(size 1.8034 0.508)
			(layers "F.Cu" "F.Mask" "F.Paste")
			(net "GND")
		)
		(pad "119" smd rect
			(at 0 105.400094 90)
			(size 1.8034 0.508)
			(layers "F.Cu" "F.Mask" "F.Paste")
			(net "M_G_DQ<49>")
		)
		(pad "120" smd rect
			(at 0 106.249978 90)
			(size 1.8034 0.508)
			(layers "F.Cu" "F.Mask" "F.Paste")
			(net "GND")
		)
		(pad "121" smd rect
			(at 0 107.100116 90)
			(size 1.8034 0.508)
			(layers "F.Cu" "F.Mask" "F.Paste")
			(net "M_G_DQS_DP<15>")
		)
		(pad "122" smd rect
			(at 0 107.95 90)
			(size 1.8034 0.508)
			(layers "F.Cu" "F.Mask" "F.Paste")
			(net "M_G_DQS_DN<15>")
		)
		(pad "123" smd rect
			(at 0 108.799884 90)
			(size 1.8034 0.508)
			(layers "F.Cu" "F.Mask" "F.Paste")
			(net "GND")
		)
		(pad "124" smd rect
			(at 0 109.650022 90)
			(size 1.8034 0.508)
			(layers "F.Cu" "F.Mask" "F.Paste")
			(net "M_G_DQ<55>")
		)
		(pad "125" smd rect
			(at 0 110.499906 90)
			(size 1.8034 0.508)
			(layers "F.Cu" "F.Mask" "F.Paste")
			(net "GND")
		)
		(pad "126" smd rect
			(at 0 111.350044 90)
			(size 1.8034 0.508)
			(layers "F.Cu" "F.Mask" "F.Paste")
			(net "M_G_DQ<51>")
		)
		(pad "127" smd rect
			(at 0 112.199928 90)
			(size 1.8034 0.508)
			(layers "F.Cu" "F.Mask" "F.Paste")
			(net "GND")
		)
		(pad "128" smd rect
			(at 0 113.050066 90)
			(size 1.8034 0.508)
			(layers "F.Cu" "F.Mask" "F.Paste")
			(net "M_G_DQ<61>")
		)
		(pad "129" smd rect
			(at 0 113.89995 90)
			(size 1.8034 0.508)
			(layers "F.Cu" "F.Mask" "F.Paste")
			(net "GND")
		)
		(pad "130" smd rect
			(at 0 114.750088 90)
			(size 1.8034 0.508)
			(layers "F.Cu" "F.Mask" "F.Paste")
			(net "M_G_DQ<57>")
		)
		(pad "131" smd rect
			(at 0 115.599972 90)
			(size 1.8034 0.508)
			(layers "F.Cu" "F.Mask" "F.Paste")
			(net "GND")
		)
		(pad "132" smd rect
			(at 0 116.45011 90)
			(size 1.8034 0.508)
			(layers "F.Cu" "F.Mask" "F.Paste")
			(net "M_G_DQS_DP<16>")
		)
		(pad "133" smd rect
			(at 0 117.299994 90)
			(size 1.8034 0.508)
			(layers "F.Cu" "F.Mask" "F.Paste")
			(net "M_G_DQS_DN<16>")
		)
		(pad "134" smd rect
			(at 0 118.149878 90)
			(size 1.8034 0.508)
			(layers "F.Cu" "F.Mask" "F.Paste")
			(net "GND")
		)
		(pad "135" smd rect
			(at 0 119.000016 90)
			(size 1.8034 0.508)
			(layers "F.Cu" "F.Mask" "F.Paste")
			(net "M_G_DQ<63>")
		)
		(pad "136" smd rect
			(at 0 119.8499 90)
			(size 1.8034 0.508)
			(layers "F.Cu" "F.Mask" "F.Paste")
			(net "GND")
		)
		(pad "137" smd rect
			(at 0 120.700038 90)
			(size 1.8034 0.508)
			(layers "F.Cu" "F.Mask" "F.Paste")
			(net "M_G_DQ<59>")
		)
		(pad "138" smd rect
			(at 0 121.549922 90)
			(size 1.8034 0.508)
			(layers "F.Cu" "F.Mask" "F.Paste")
			(net "GND")
		)
		(pad "139" smd rect
			(at 0 122.40006 90)
			(size 1.8034 0.508)
			(layers "F.Cu" "F.Mask" "F.Paste")
			(net "GND")
		)
		(pad "140" smd rect
			(at 0 123.249944 90)
			(size 1.8034 0.508)
			(layers "F.Cu" "F.Mask" "F.Paste")
			(net "GND")
		)
		(pad "141" smd rect
			(at 0 124.100082 90)
			(size 1.8034 0.508)
			(layers "F.Cu" "F.Mask" "F.Paste")
			(net "SMB_DDR_GHJ_VPP_SCL")
		)
		(pad "142" smd rect
			(at 0 124.949966 90)
			(size 1.8034 0.508)
			(layers "F.Cu" "F.Mask" "F.Paste")
			(net "PVPP_GHJ")
		)
		(pad "143" smd rect
			(at 0 125.800104 90)
			(size 1.8034 0.508)
			(layers "F.Cu" "F.Mask" "F.Paste")
			(net "PVPP_GHJ")
		)
		(pad "144" smd rect
			(at 0 126.649988 90)
			(size 1.8034 0.508)
			(layers "F.Cu" "F.Mask" "F.Paste")
			(net "TP_CH_G_DIMM_G0_RFU_2")
		)
		(pad "145" smd rect
			(at 4.59994 0 90)
			(size 1.8034 0.508)
			(layers "F.Cu" "F.Mask" "F.Paste")
			(net "P12V_NVDIMM_GHJ")
		)
		(pad "146" smd rect
			(at 4.59994 0.849884 90)
			(size 1.8034 0.508)
			(layers "F.Cu" "F.Mask" "F.Paste")
			(net "M_G_VREF")
		)
		(pad "147" smd rect
			(at 4.59994 1.700022 90)
			(size 1.8034 0.508)
			(layers "F.Cu" "F.Mask" "F.Paste")
			(net "GND")
		)
		(pad "148" smd rect
			(at 4.59994 2.549906 90)
			(size 1.8034 0.508)
			(layers "F.Cu" "F.Mask" "F.Paste")
			(net "M_G_DQ<4>")
		)
	)
)
